(kicad_pcb
	(version 20221018)
	(generator pcbnew)
	(general
    (thickness 1.62)
  )
	(paper "A4")
	(title_block
    (title "ECP5 - Datacenter Secure Control Module (DC-SCM)")
    (date "2024-07-01")
    (rev "1.2.1")
		(comment 9 "footprints 1-6 of 506")
	)
	(layers
    (0 "F.Cu" signal)
    (1 "In1.Cu" power)
    (2 "In2.Cu" signal)
    (3 "In3.Cu" power)
    (4 "In4.Cu" power)
    (5 "In5.Cu" signal)
    (6 "In6.Cu" power)
    (31 "B.Cu" signal)
    (32 "B.Adhes" user "B.Adhesive")
    (33 "F.Adhes" user "F.Adhesive")
    (34 "B.Paste" user)
    (35 "F.Paste" user)
    (36 "B.SilkS" user "B.Silkscreen")
    (37 "F.SilkS" user "F.Silkscreen")
    (38 "B.Mask" user)
    (39 "F.Mask" user)
    (40 "Dwgs.User" user "User.Drawings")
    (41 "Cmts.User" user "User.Comments")
    (42 "Eco1.User" user "User.Eco1")
    (43 "Eco2.User" user "User.Eco2")
    (44 "Edge.Cuts" user)
    (45 "Margin" user)
    (46 "B.CrtYd" user "B.Courtyard")
    (47 "F.CrtYd" user "F.Courtyard")
    (48 "B.Fab" user)
    (49 "F.Fab" user)
  )
	(footprint "antmicro-footprints:R_0402_1005Metric" (layer "F.Cu")
    (at 71.4 124.67 90)
    (descr "Resistor SMD 0402")
    (tags "resistor SMD 0402")
    (property "Author" "Antmicro")
    (property "License" "Apache-2.0")
    (property "MPN" "CR0402-FX-1002GLF")
    (property "Manufacturer" "Bourns")
    (property "Public" "False")
    (property "Sheetfile" "ddr3.kicad_sch")
    (property "Sheetname" "DDR3")
    (property "Tolerance" "1%")
    (property "Val" "10k")
    (property "ki_description" "SMD Chip Resistor, 10 kohm, ± 1%, 62.5 mW, 0402 [1005 Metric], Thick Film, General Purpose")
    (property "ki_keywords" "0402, SMT, RESISTOR, PASSIVE")
    (attr smd)
    (fp_text reference "R79" (at -3.38 -0.03 90) (layer "F.SilkS")
        (effects (font (size 0.7 0.7) (thickness 0.127)))
    )
    (fp_text value "R_10k_0402" (at 0 1.17 90) (layer "F.Fab")
        (effects (font (size 1 1) (thickness 0.15)))
    )
    (fp_text user "${REFERENCE}" (at 0 0 90) (layer "F.Fab")
        (effects (font (size 0.25 0.25) (thickness 0.04)))
    )
    (fp_text user "Author: Antmicro" (at -0.95 4.169 90) (layer "F.Fab") hide
        (effects (font (size 0.7 0.7) (thickness 0.15)) (justify left bottom))
    )
    (fp_text user "License: Apache-2.0" (at -0.95 5.169 90) (layer "F.Fab") hide
        (effects (font (size 0.7 0.7) (thickness 0.15)) (justify left bottom))
    )
    (fp_rect (start -0.925 -0.47) (end 0.925 0.47)
      (stroke (width 0.05) (type default)) (fill none) (layer "F.CrtYd"))
    (fp_rect (start -0.5 -0.25) (end 0.5 0.25)
      (stroke (width 0.15) (type solid)) (fill none) (layer "F.Fab"))
    (pad "1" smd roundrect (at -0.48 0 90) (size 0.59 0.64) (layers "F.Cu" "F.Paste" "F.Mask") (roundrect_rratio 0.25)
      (net 3 "VCC1V35") (pintype "passive"))
    (pad "2" smd roundrect (at 0.48 0 90) (size 0.59 0.64) (layers "F.Cu" "F.Paste" "F.Mask") (roundrect_rratio 0.25)
      (net 305 "Net-(U11-REFIN)") (pintype "passive"))
  )
	(footprint "antmicro-footprints:R_0402_1005Metric" (layer "F.Cu")
    (at 74.45 61.2)
    (descr "Resistor SMD 0402")
    (tags "resistor SMD 0402")
    (property "Author" "Antmicro")
    (property "License" "Apache-2.0")
    (property "MPN" "CR0402-FX-49R9GLF")
    (property "Manufacturer" "Bourns")
    (property "Public" "False")
    (property "Sheetfile" "power-supply.kicad_sch")
    (property "Sheetname" "Power supply")
    (property "Tolerance" "1%")
    (property "Val" "49R9")
    (property "ki_description" "SMD Chip Resistor, 49.9 ohm, ± 1%, 62.5 mW, 0402 [1005 Metric], Thick Film, General Purpose")
    (property "ki_keywords" "0402, SMT, RESISTOR, PASSIVE")
    (attr smd)
    (fp_text reference "R95" (at -0.6 -1.75) (layer "F.SilkS")
        (effects (font (size 0.7 0.7) (thickness 0.127)))
    )
    (fp_text value "R_49R9_0402" (at 0 1.17) (layer "F.Fab")
        (effects (font (size 1 1) (thickness 0.15)))
    )
    (fp_text user "${REFERENCE}" (at 0 0) (layer "F.Fab")
        (effects (font (size 0.25 0.25) (thickness 0.04)))
    )
    (fp_text user "License: Apache-2.0" (at -0.95 5.169) (layer "F.Fab") hide
        (effects (font (size 0.7 0.7) (thickness 0.15)) (justify left bottom))
    )
    (fp_text user "Author: Antmicro" (at -0.95 4.169) (layer "F.Fab") hide
        (effects (font (size 0.7 0.7) (thickness 0.15)) (justify left bottom))
    )
    (fp_rect (start -0.925 -0.47) (end 0.925 0.47)
      (stroke (width 0.05) (type default)) (fill none) (layer "F.CrtYd"))
    (fp_rect (start -0.5 -0.25) (end 0.5 0.25)
      (stroke (width 0.15) (type solid)) (fill none) (layer "F.Fab"))
    (pad "1" smd roundrect (at -0.48 0) (size 0.59 0.64) (layers "F.Cu" "F.Paste" "F.Mask") (roundrect_rratio 0.25)
      (net 290 "Net-(C110-Pad2)") (pintype "passive"))
    (pad "2" smd roundrect (at 0.48 0) (size 0.59 0.64) (layers "F.Cu" "F.Paste" "F.Mask") (roundrect_rratio 0.25)
      (net 364 "Net-(R95-Pad2)") (pintype "passive"))
  )
	(footprint "antmicro-footprints:C_0603_1608Metric" (layer "F.Cu")
    (at 76.85 68.65 -90)
    (descr "Capacitor SMD 0603")
    (tags "capacitor 0603")
    (property "Author" "Antmicro")
    (property "Dielectric" "")
    (property "License" "Apache-2.0")
    (property "MPN" "GRM188R60J476ME15D")
    (property "Manufacturer" "Murata")
    (property "Public" "False")
    (property "Sheetfile" "power-supply.kicad_sch")
    (property "Sheetname" "Power supply")
    (property "Val" "47u")
    (property "Voltage" "")
    (property "ki_description" "SMD Multilayer Ceramic Capacitor, 47 µF, 6.3 V, 0603 [1608 Metric], ± 20%, X5R, GRM Series")
    (property "ki_keywords" "0603, SMT, CAPACITOR, PASSIVE, CERAMIC, MLCC")
    (attr smd)
    (fp_text reference "C110" (at -0.065 2.37 90) (layer "F.SilkS")
        (effects (font (size 0.7 0.7) (thickness 0.127)))
    )
    (fp_text value "C_47u_0603" (at 0 1.91 90) (layer "F.Fab")
        (effects (font (size 1 1) (thickness 0.15)))
    )
    (fp_text user "Author: Antmicro" (at -1.682 4.894 -90) (layer "F.Fab") hide
        (effects (font (size 0.7 0.7) (thickness 0.15)) (justify left bottom))
    )
    (fp_text user "License: Apache-2.0" (at -1.682 5.895 -90) (layer "F.Fab") hide
        (effects (font (size 0.7 0.7) (thickness 0.15)) (justify left bottom))
    )
    (fp_text user "${REFERENCE}" (at -1.682 3.895 -90) (layer "F.Fab") hide
        (effects (font (size 0.7 0.7) (thickness 0.15)) (justify left bottom))
    )
    (fp_line (start -0.15 -0.4) (end 0.15 -0.4)
      (stroke (width 0.15) (type solid)) (layer "F.SilkS"))
    (fp_line (start -0.15 0.4) (end 0.15 0.4)
      (stroke (width 0.15) (type solid)) (layer "F.SilkS"))
    (fp_rect (start -1.25 -0.65) (end 1.25 0.65)
      (stroke (width 0.05) (type solid)) (fill none) (layer "F.CrtYd"))
    (fp_rect (start -0.8 -0.4) (end 0.8 0.4)
      (stroke (width 0.15) (type solid)) (fill none) (layer "F.Fab"))
    (pad "1" smd roundrect (at -0.7 0 270) (size 0.8 1) (layers "F.Cu" "F.Paste" "F.Mask") (roundrect_rratio 0.2)
      (net 1 "GND") (pintype "passive"))
    (pad "2" smd roundrect (at 0.7 0 270) (size 0.8 1) (layers "F.Cu" "F.Paste" "F.Mask") (roundrect_rratio 0.2)
      (net 290 "Net-(C110-Pad2)") (pintype "passive"))
  )
	(footprint "antmicro-footprints:WSON-10-1EP_4x4mm_P0.8mm_EP2.6x3mm" (layer "F.Cu")
    (at 78.8 65 180)
    (property "Author" "Antmicro")
    (property "License" "Apache-2.0")
    (property "MPN" "TPS54561QDPRRQ1")
    (property "Manufacturer" "Texas Instruments")
    (property "Sheetfile" "power-supply.kicad_sch")
    (property "Sheetname" "Power supply")
    (property "ki_description" "DC/DC converter")
    (property "ki_keywords" "SMT, PMIC, IC, SWITCHING, VOLTAGE, REGULATOR, DC-DC")
    (attr smd)
    (fp_text reference "U15" (at 1.5 3.335) (layer "F.SilkS")
        (effects (font (size 0.7 0.7) (thickness 0.15)) (justify left bottom))
    )
    (fp_text value "TPS54561QDPRRQ1" (at 0 3.4) (layer "F.Fab")
        (effects (font (size 0.7 0.7) (thickness 0.15)) (justify left bottom))
    )
    (fp_text user "Author: Antmicro" (at -2.52 6.6 180) (layer "F.Fab") hide
        (effects (font (size 0.7 0.7) (thickness 0.15)) (justify left bottom))
    )
    (fp_text user "License: Apache-2.0" (at -2.52 7.8 180) (layer "F.Fab") hide
        (effects (font (size 0.7 0.7) (thickness 0.15)) (justify left bottom))
    )
    (fp_text user "${REFERENCE}" (at -2.52 5.4 180) (layer "F.Fab") hide
        (effects (font (size 0.7 0.7) (thickness 0.15)) (justify left bottom))
    )
    (fp_line (start -2.1 -2.123) (end -2.1 -1.975)
      (stroke (width 0.15) (type solid)) (layer "F.SilkS"))
    (fp_line (start -2.1 -2.123) (end 2.1 -2.123)
      (stroke (width 0.15) (type solid)) (layer "F.SilkS"))
    (fp_line (start -2.1 2.123) (end -2.1 1.975)
      (stroke (width 0.15) (type solid)) (layer "F.SilkS"))
    (fp_line (start 2.1 -2.123) (end 2.1 -1.975)
      (stroke (width 0.15) (type solid)) (layer "F.SilkS"))
    (fp_line (start 2.1 2.122) (end -2.1 2.122)
      (stroke (width 0.15) (type solid)) (layer "F.SilkS"))
    (fp_line (start 2.1 2.122) (end 2.1 1.975)
      (stroke (width 0.15) (type solid)) (layer "F.SilkS"))
    (fp_circle (center -2.325 -2.05) (end -2.275 -2.05)
      (stroke (width 0.15) (type solid)) (fill solid) (layer "F.SilkS"))
    (fp_rect (start -2.57 -2.2) (end 2.469 2.2)
      (stroke (width 0.05) (type solid)) (fill none) (layer "F.CrtYd"))
    (fp_line (start -2 -1.5) (end -1.5 -2)
      (stroke (width 0.15) (type solid)) (layer "F.Fab"))
    (fp_line (start -2 2) (end -2 -1.5)
      (stroke (width 0.15) (type solid)) (layer "F.Fab"))
    (fp_line (start -1.5 -2) (end 2 -2)
      (stroke (width 0.15) (type solid)) (layer "F.Fab"))
    (fp_line (start 2 -2) (end 2 2)
      (stroke (width 0.15) (type solid)) (layer "F.Fab"))
    (fp_line (start 2 2) (end -2 2)
      (stroke (width 0.15) (type solid)) (layer "F.Fab"))
    (pad "1" smd roundrect (at -1.9 -1.6 270) (size 0.3 0.6) (layers "F.Cu" "F.Paste" "F.Mask") (roundrect_rratio 0.1666666667)
      (net 782 "Net-(U15-BOOT)") (pinfunction "BOOT") (pintype "output"))
    (pad "2" smd roundrect (at -1.9 -0.8 270) (size 0.3 0.6) (layers "F.Cu" "F.Paste" "F.Mask") (roundrect_rratio 0.1666666667)
      (net 15 "VCC12V") (pinfunction "V_{DD}") (pintype "power_in"))
    (pad "3" smd roundrect (at -1.9 0 270) (size 0.3 0.6) (layers "F.Cu" "F.Paste" "F.Mask") (roundrect_rratio 0.1666666667)
      (net 785 "Net-(U15-EN)") (pinfunction "EN") (pintype "input"))
    (pad "4" smd roundrect (at -1.9 0.8 270) (size 0.3 0.6) (layers "F.Cu" "F.Paste" "F.Mask") (roundrect_rratio 0.1666666667)
      (net 780 "Net-(U15-SS{slash}TR)") (pinfunction "SS/TR") (pintype "input"))
    (pad "5" smd roundrect (at -1.9 1.6 270) (size 0.3 0.6) (layers "F.Cu" "F.Paste" "F.Mask") (roundrect_rratio 0.1666666667)
      (net 783 "Net-(U15-RT{slash}CLK)") (pinfunction "RT/CLK") (pintype "input"))
    (pad "6" smd roundrect (at 1.9 1.6 270) (size 0.3 0.6) (layers "F.Cu" "F.Paste" "F.Mask") (roundrect_rratio 0.1666666667)
      (net 784 "Net-(U15-FB)") (pinfunction "FB") (pintype "input"))
    (pad "7" smd roundrect (at 1.9 0.8 270) (size 0.3 0.6) (layers "F.Cu" "F.Paste" "F.Mask") (roundrect_rratio 0.1666666667)
      (net 781 "Net-(U15-COMP)") (pinfunction "COMP") (pintype "output"))
    (pad "8" smd roundrect (at 1.9 0 270) (size 0.3 0.6) (layers "F.Cu" "F.Paste" "F.Mask") (roundrect_rratio 0.1666666667)
      (net 1 "GND") (pinfunction "GND") (pintype "power_in"))
    (pad "9" smd roundrect (at 1.9 -0.8 270) (size 0.3 0.6) (layers "F.Cu" "F.Paste" "F.Mask") (roundrect_rratio 0.1666666667)
      (net 265 "Net-(D6-C)") (pinfunction "SW") (pintype "power_out"))
    (pad "10" smd roundrect (at 1.9 -1.6 270) (size 0.3 0.6) (layers "F.Cu" "F.Paste" "F.Mask") (roundrect_rratio 0.1666666667)
      (net 270 "/Power supply/5V0_PG") (pinfunction "PWRGD") (pintype "output"))
    (pad "11" smd roundrect (at 0 0 180) (size 2.6 3) (layers "F.Cu" "F.Paste" "F.Mask") (roundrect_rratio 0.01923076923)
      (net 1 "GND") (pinfunction "GND") (pintype "passive"))
  )
	(footprint "antmicro-footprints:C_0603_1608Metric" (layer "F.Cu")
    (at 78.35 68.65 -90)
    (descr "Capacitor SMD 0603")
    (tags "capacitor 0603")
    (property "Author" "Antmicro")
    (property "Dielectric" "")
    (property "License" "Apache-2.0")
    (property "MPN" "GRM188R60J476ME15D")
    (property "Manufacturer" "Murata")
    (property "Public" "False")
    (property "Sheetfile" "power-supply.kicad_sch")
    (property "Sheetname" "Power supply")
    (property "Val" "47u")
    (property "Voltage" "")
    (property "ki_description" "SMD Multilayer Ceramic Capacitor, 47 µF, 6.3 V, 0603 [1608 Metric], ± 20%, X5R, GRM Series")
    (property "ki_keywords" "0603, SMT, CAPACITOR, PASSIVE, CERAMIC, MLCC")
    (attr smd)
    (fp_text reference "C111" (at -0.065 2.94 90) (layer "F.SilkS")
        (effects (font (size 0.7 0.7) (thickness 0.127)))
    )
    (fp_text value "C_47u_0603" (at 0 1.9 90) (layer "F.Fab")
        (effects (font (size 1 1) (thickness 0.15)))
    )
    (fp_text user "License: Apache-2.0" (at -1.682 5.895 -90) (layer "F.Fab") hide
        (effects (font (size 0.7 0.7) (thickness 0.15)) (justify left bottom))
    )
    (fp_text user "${REFERENCE}" (at -1.682 3.895 -90) (layer "F.Fab") hide
        (effects (font (size 0.7 0.7) (thickness 0.15)) (justify left bottom))
    )
    (fp_text user "Author: Antmicro" (at -1.682 4.894 -90) (layer "F.Fab") hide
        (effects (font (size 0.7 0.7) (thickness 0.15)) (justify left bottom))
    )
    (fp_line (start -0.15 -0.4) (end 0.15 -0.4)
      (stroke (width 0.15) (type solid)) (layer "F.SilkS"))
    (fp_line (start -0.15 0.4) (end 0.15 0.4)
      (stroke (width 0.15) (type solid)) (layer "F.SilkS"))
    (fp_rect (start -1.25 -0.65) (end 1.25 0.65)
      (stroke (width 0.05) (type solid)) (fill none) (layer "F.CrtYd"))
    (fp_rect (start -0.8 -0.4) (end 0.8 0.4)
      (stroke (width 0.15) (type solid)) (fill none) (layer "F.Fab"))
    (pad "1" smd roundrect (at -0.7 0 270) (size 0.8 1) (layers "F.Cu" "F.Paste" "F.Mask") (roundrect_rratio 0.2)
      (net 1 "GND") (pintype "passive"))
    (pad "2" smd roundrect (at 0.7 0 270) (size 0.8 1) (layers "F.Cu" "F.Paste" "F.Mask") (roundrect_rratio 0.2)
      (net 290 "Net-(C110-Pad2)") (pintype "passive"))
  )
	(footprint "antmicro-footprints:VSON-10-1EP_3x3mm" (layer "F.Cu")
    (at 73.822 120.904 90)
    (property "Author" "Antmicro")
    (property "License" "Apache-2.0")
    (property "MPN" "TPS51200DRCT")
    (property "Manufacturer" "Texas Instruments")
    (property "Sheetfile" "ddr3.kicad_sch")
    (property "Sheetname" "DDR3")
    (property "ki_description" "Fixed LDO Voltage Regulator, 2.375 V to 3.5 V, 0.8 V Dropout, 1.25 V / 3 A out, VSON-10")
    (property "ki_keywords" "SMT, PMIC, IC")
    (attr smd)
    (fp_text reference "U11" (at -1.051 2.588 90) (layer "F.SilkS")
        (effects (font (size 0.7 0.7) (thickness 0.15)) (justify left bottom))
    )
    (fp_text value "TPS51200DRCT" (at -2 2.7 90) (layer "F.Fab")
        (effects (font (size 0.7 0.7) (thickness 0.15)) (justify left bottom))
    )
    (fp_text user "." (at -2.05 -1.65 90) (layer "F.SilkS") hide
        (effects (font (size 0.7 0.7) (thickness 0.15)) (justify left bottom))
    )
    (fp_text user "Author: Antmicro" (at -2 4.7 90) (layer "F.Fab") hide
        (effects (font (size 0.7 0.7) (thickness 0.15)) (justify left bottom))
    )
    (fp_text user "${REFERENCE}" (at -2 5.9 90) (layer "F.Fab") hide
        (effects (font (size 0.7 0.7) (thickness 0.15)) (justify left bottom))
    )
    (fp_text user "License: Apache-2.0" (at -2 7.1 90) (layer "F.Fab") hide
        (effects (font (size 0.7 0.7) (thickness 0.15)) (justify left bottom))
    )
    (fp_line (start -1.5 1.598) (end 1.499 1.598)
      (stroke (width 0.15) (type solid)) (layer "F.SilkS"))
    (fp_line (start 0 -1.621) (end 1.499 -1.621)
      (stroke (width 0.15) (type solid)) (layer "F.SilkS"))
    (fp_line (start -1.97 1.215) (end -1.97 -1.24)
      (stroke (width 0.05) (type solid)) (layer "F.CrtYd"))
    (fp_line (start -1.65 -1.65) (end -1.65 -1.24)
      (stroke (width 0.05) (type solid)) (layer "F.CrtYd"))
    (fp_line (start -1.65 -1.24) (end -1.97 -1.24)
      (stroke (width 0.05) (type solid)) (layer "F.CrtYd"))
    (fp_line (start -1.65 1.215) (end -1.97 1.215)
      (stroke (width 0.05) (type solid)) (layer "F.CrtYd"))
    (fp_line (start -1.65 1.215) (end -1.65 1.625)
      (stroke (width 0.05) (type solid)) (layer "F.CrtYd"))
    (fp_line (start -1.65 1.625) (end 1.65 1.625)
      (stroke (width 0.05) (type solid)) (layer "F.CrtYd"))
    (fp_line (start 1.65 -1.65) (end -1.65 -1.65)
      (stroke (width 0.05) (type solid)) (layer "F.CrtYd"))
    (fp_line (start 1.65 -1.24) (end 1.65 -1.65)
      (stroke (width 0.05) (type solid)) (layer "F.CrtYd"))
    (fp_line (start 1.65 -1.24) (end 1.97 -1.24)
      (stroke (width 0.05) (type solid)) (layer "F.CrtYd"))
    (fp_line (start 1.65 1.215) (end 1.97 1.215)
      (stroke (width 0.05) (type solid)) (layer "F.CrtYd"))
    (fp_line (start 1.65 1.625) (end 1.65 1.215)
      (stroke (width 0.05) (type solid)) (layer "F.CrtYd"))
    (fp_line (start 1.97 -1.24) (end 1.97 1.215)
      (stroke (width 0.05) (type solid)) (layer "F.CrtYd"))
    (fp_line (start -1.5 -0.76) (end -0.75 -1.51)
      (stroke (width 0.15) (type solid)) (layer "F.Fab"))
    (fp_line (start -1.5 1.489) (end -1.5 -0.76)
      (stroke (width 0.15) (type solid)) (layer "F.Fab"))
    (fp_line (start -0.75 -1.51) (end 1.499 -1.51)
      (stroke (width 0.15) (type solid)) (layer "F.Fab"))
    (fp_line (start 1.499 -1.51) (end 1.499 1.489)
      (stroke (width 0.15) (type solid)) (layer "F.Fab"))
    (fp_line (start 1.499 1.489) (end -1.5 1.489)
      (stroke (width 0.15) (type solid)) (layer "F.Fab"))
    (pad "" smd roundrect (at -0.3 -0.51 90) (size 0.48 0.81) (layers "F.Paste") (roundrect_rratio 0.25))
    (pad "" smd roundrect (at -0.3 0.488 90) (size 0.48 0.81) (layers "F.Paste") (roundrect_rratio 0.25))
    (pad "" smd roundrect (at 0.299 -0.51 90) (size 0.48 0.81) (layers "F.Paste") (roundrect_rratio 0.25))
    (pad "" smd roundrect (at 0.299 0.488 90) (size 0.48 0.81) (layers "F.Paste") (roundrect_rratio 0.25))
    (pad "1" smd roundrect (at -1.438 -1.01 90) (size 0.875 0.25) (layers "F.Cu" "F.Paste" "F.Mask") (roundrect_rratio 0.25)
      (net 305 "Net-(U11-REFIN)") (pinfunction "REFIN") (pintype "input"))
    (pad "2" smd roundrect (at -1.438 -0.51 90) (size 0.875 0.25) (layers "F.Cu" "F.Paste" "F.Mask") (roundrect_rratio 0.25)
      (net 3 "VCC1V35") (pinfunction "VLDOIN") (pintype "power_in"))
    (pad "3" smd roundrect (at -1.438 -0.011 90) (size 0.875 0.25) (layers "F.Cu" "F.Paste" "F.Mask") (roundrect_rratio 0.25)
      (net 166 "/DDR3/DDR3_VTT") (pinfunction "VO") (pintype "power_out"))
    (pad "4" smd roundrect (at -1.438 0.488 90) (size 0.875 0.25) (layers "F.Cu" "F.Paste" "F.Mask") (roundrect_rratio 0.25)
      (net 1 "GND") (pinfunction "GND") (pintype "passive"))
    (pad "5" smd roundrect (at -1.438 0.988 90) (size 0.875 0.25) (layers "F.Cu" "F.Paste" "F.Mask") (roundrect_rratio 0.25)
      (net 166 "/DDR3/DDR3_VTT") (pinfunction "VOSNS") (pintype "input"))
    (pad "6" smd roundrect (at 1.437 0.988 90) (size 0.875 0.25) (layers "F.Cu" "F.Paste" "F.Mask") (roundrect_rratio 0.25)
      (net 217 "DDR3_VREF") (pinfunction "REFOUT") (pintype "power_out"))
    (pad "7" smd roundrect (at 1.437 0.488 90) (size 0.875 0.25) (layers "F.Cu" "F.Paste" "F.Mask") (roundrect_rratio 0.25)
      (net 430 "DDR3_VTT_EN") (pinfunction "EN") (pintype "input"))
    (pad "8" smd roundrect (at 1.437 -0.011 90) (size 0.875 0.25) (layers "F.Cu" "F.Paste" "F.Mask") (roundrect_rratio 0.25)
      (net 1 "GND") (pinfunction "GND") (pintype "power_in"))
    (pad "9" smd roundrect (at 1.437 -0.51 90) (size 0.875 0.25) (layers "F.Cu" "F.Paste" "F.Mask") (roundrect_rratio 0.25)
      (net 408 "Net-(U11-PGOOD)") (pinfunction "PGOOD") (pintype "open_collector"))
    (pad "10" smd roundrect (at 1.437 -1.01 90) (size 0.875 0.25) (layers "F.Cu" "F.Paste" "F.Mask") (roundrect_rratio 0.25)
      (net 2 "VCC3V3") (pinfunction "VIN") (pintype "power_in"))
    (pad "11" smd roundrect (at 0 -0.011 90) (size 1.2 2) (layers "F.Cu" "F.Mask") (roundrect_rratio 0.208333)
      (net 1 "GND") (pinfunction "GND") (pintype "passive"))
  )
)
